# T6G (Grand Teton) — schematic netlist excerpt (pin names and nets, part order shuffled) for the footprints in the layout excerpt that follows; sources: Cadence DE-HDL packaged netlist, KiCad conversion of 04192023_DAF0TMB3IC0_F0TG_MB_C_brd_V02_OCP.brd

TP7  TP  NA  pkg TP  page 27 : TP = VSENSE_PVDDCR_CPU0_P0_DP
PC318_8  Q_CAP  0.1UF 25V 10% X7R  pkg 0402  page 215 : A = PVDDCR_CPU0_P1_VCCS ; B = GND
PR6502  Q_RES  7.15K 1% CHIP  pkg 0402LF  page 360 : A = P1V8_RETIMER_CPU0_CS ; B = GND

(kicad_pcb
	(version 20260206)
	(generator "pcbnew")
	(generator_version "10.0")
	(general
		(thickness 1.6)
		(legacy_teardrops no)
	)
	(paper "A4")
	(title_block
		(title "04192023_DAF0TMB3IC0_F0TG_MB_C_brd_V02_OCP.brd")
		(comment 1 "Grand Teton / footprints 4250-4252 of 8354")
	)
	(layers
		(0 "F.Cu" signal "TOP")
		(4 "In1.Cu" signal "GND")
		(6 "In2.Cu" signal "IN1")
		(8 "In3.Cu" signal "GND1")
		(10 "In4.Cu" signal "IN2")
		(12 "In5.Cu" signal "GND2")
		(14 "In6.Cu" signal "IN3")
		(16 "In7.Cu" signal "GND3")
		(18 "In8.Cu" signal "VCC")
		(20 "In9.Cu" signal "VCC1")
		(22 "In10.Cu" signal "GND4")
		(24 "In11.Cu" signal "IN4")
		(26 "In12.Cu" signal "GND5")
		(28 "In13.Cu" signal "IN5")
		(30 "In14.Cu" signal "GND6")
		(32 "In15.Cu" signal "IN6")
		(34 "In16.Cu" signal "GND7")
		(2 "B.Cu" signal "BOTTOM")
		(9 "F.Adhes" user "F.Adhesive")
		(11 "B.Adhes" user "B.Adhesive")
		(13 "F.Paste" user "Package Geometry/Pastemask Top")
		(15 "B.Paste" user "Package Geometry/Pastemask Bottom")
		(5 "F.SilkS" user "Ref Des/Silkscreen Top")
		(7 "B.SilkS" user "Ref Des/Silkscreen Bottom")
		(1 "F.Mask" user "Board Geometry/Soldermask Top")
		(3 "B.Mask" user "Board Geometry/Soldermask Bottom")
		(17 "Dwgs.User" user "User.Drawings")
		(19 "Cmts.User" user "User.Comments")
		(21 "Eco1.User" user "User.Eco1")
		(23 "Eco2.User" user "User.Eco2")
		(25 "Edge.Cuts" user "Board Geometry/Outline")
		(27 "Margin" user)
		(31 "F.CrtYd" user "Package Geometry/Place Bound Top")
		(29 "B.CrtYd" user "Package Geometry/Place Bound Bottom")
		(35 "F.Fab" user "Ref Des/Assembly Top")
		(33 "B.Fab" user "Ref Des/Assembly Bottom")
	)
	(footprint ""
		(layer "F.Cu")
		(at 126.659894 -160.33496 -90)
		(property "Reference" "PC318_8"
			(at 0 0 270)
			(layer "F.SilkS")
			(hide yes)
			(effects
				(font
					(size 1.27 1.27)
				)
			)
		)
		(property "Value" ""
			(at 0 0 270)
			(layer "F.Fab")
			(effects
				(font
					(size 1.27 1.27)
				)
			)
		)
		(duplicate_pad_numbers_are_jumpers no)
		(fp_line
			(start -0.7874 0.4064)
			(end -0.7874 -0.4064)
			(stroke
				(width 0.1524)
				(type default)
			)
			(layer "F.SilkS")
		)
		(fp_line
			(start 0.7874 0.4064)
			(end -0.7874 0.4064)
			(stroke
				(width 0.1524)
				(type default)
			)
			(layer "F.SilkS")
		)
		(fp_line
			(start -0.7874 -0.4064)
			(end 0.7874 -0.4064)
			(stroke
				(width 0.1524)
				(type default)
			)
			(layer "F.SilkS")
		)
		(fp_line
			(start 0.7874 -0.4064)
			(end 0.7874 0.4064)
			(stroke
				(width 0.1524)
				(type default)
			)
			(layer "F.SilkS")
		)
		(fp_line
			(start -0.67945 0.3048)
			(end -0.67945 -0.305054)
			(stroke
				(width 0.1)
				(type default)
			)
			(layer "F.Fab")
		)
		(fp_line
			(start -0.12065 0.3048)
			(end -0.67945 0.3048)
			(stroke
				(width 0.1)
				(type default)
			)
			(layer "F.Fab")
		)
		(fp_line
			(start 0.120396 0.3048)
			(end 0.120396 0.2794)
			(stroke
				(width 0.1)
				(type default)
			)
			(layer "F.Fab")
		)
		(fp_line
			(start 0.67945 0.3048)
			(end 0.120396 0.3048)
			(stroke
				(width 0.1)
				(type default)
			)
			(layer "F.Fab")
		)
		(fp_line
			(start -0.12065 0.2794)
			(end -0.12065 0.3048)
			(stroke
				(width 0.1)
				(type default)
			)
			(layer "F.Fab")
		)
		(fp_line
			(start 0.120396 0.2794)
			(end -0.12065 0.2794)
			(stroke
				(width 0.1)
				(type default)
			)
			(layer "F.Fab")
		)
		(fp_line
			(start -0.12065 -0.2794)
			(end 0.12065 -0.2794)
			(stroke
				(width 0.1)
				(type default)
			)
			(layer "F.Fab")
		)
		(fp_line
			(start 0.12065 -0.2794)
			(end 0.12065 -0.3048)
			(stroke
				(width 0.1)
				(type default)
			)
			(layer "F.Fab")
		)
		(fp_line
			(start 0.12065 -0.3048)
			(end 0.67945 -0.3048)
			(stroke
				(width 0.1)
				(type default)
			)
			(layer "F.Fab")
		)
		(fp_line
			(start 0.67945 -0.3048)
			(end 0.67945 0.3048)
			(stroke
				(width 0.1)
				(type default)
			)
			(layer "F.Fab")
		)
		(fp_line
			(start -0.67945 -0.305054)
			(end -0.12065 -0.305054)
			(stroke
				(width 0.1)
				(type default)
			)
			(layer "F.Fab")
		)
		(fp_line
			(start -0.12065 -0.305054)
			(end -0.12065 -0.2794)
			(stroke
				(width 0.1)
				(type default)
			)
			(layer "F.Fab")
		)
		(pad "1" smd circle
			(at -0.40005 0 270)
			(size 0 0)
			(layers "F.Cu" "F.Mask" "F.Paste")
			(net "PVDDCR_CPU0_P1_VCCS")
		)
		(pad "2" smd circle
			(at 0.40005 0 270)
			(size 0 0)
			(layers "F.Cu" "F.Mask" "F.Paste")
			(net "GND")
		)
	)
	(footprint ""
		(layer "F.Cu")
		(at 239.53597 -292.988238 180)
		(property "Reference" "PR6502"
			(at 0 0 180)
			(layer "F.SilkS")
			(hide yes)
			(effects
				(font
					(size 1.27 1.27)
				)
			)
		)
		(property "Value" ""
			(at 0 0 180)
			(layer "F.Fab")
			(effects
				(font
					(size 1.27 1.27)
				)
			)
		)
		(duplicate_pad_numbers_are_jumpers no)
		(fp_line
			(start 0.7874 0.4064)
			(end -0.7874 0.4064)
			(stroke
				(width 0.1524)
				(type default)
			)
			(layer "F.SilkS")
		)
		(fp_line
			(start 0.7874 -0.4064)
			(end 0.7874 0.4064)
			(stroke
				(width 0.1524)
				(type default)
			)
			(layer "F.SilkS")
		)
		(fp_line
			(start -0.7874 0.4064)
			(end -0.7874 -0.4064)
			(stroke
				(width 0.1524)
				(type default)
			)
			(layer "F.SilkS")
		)
		(fp_line
			(start -0.7874 -0.4064)
			(end 0.7874 -0.4064)
			(stroke
				(width 0.1524)
				(type default)
			)
			(layer "F.SilkS")
		)
		(fp_line
			(start 0.67945 0.3048)
			(end 0.120396 0.3048)
			(stroke
				(width 0.1)
				(type default)
			)
			(layer "F.Fab")
		)
		(fp_line
			(start 0.67945 -0.3048)
			(end 0.67945 0.3048)
			(stroke
				(width 0.1)
				(type default)
			)
			(layer "F.Fab")
		)
		(fp_line
			(start 0.12065 -0.2794)
			(end 0.12065 -0.3048)
			(stroke
				(width 0.1)
				(type default)
			)
			(layer "F.Fab")
		)
		(fp_line
			(start 0.12065 -0.3048)
			(end 0.67945 -0.3048)
			(stroke
				(width 0.1)
				(type default)
			)
			(layer "F.Fab")
		)
		(fp_line
			(start 0.120396 0.3048)
			(end 0.120396 0.2794)
			(stroke
				(width 0.1)
				(type default)
			)
			(layer "F.Fab")
		)
		(fp_line
			(start 0.120396 0.2794)
			(end -0.12065 0.2794)
			(stroke
				(width 0.1)
				(type default)
			)
			(layer "F.Fab")
		)
		(fp_line
			(start -0.12065 0.3048)
			(end -0.67945 0.3048)
			(stroke
				(width 0.1)
				(type default)
			)
			(layer "F.Fab")
		)
		(fp_line
			(start -0.12065 0.2794)
			(end -0.12065 0.3048)
			(stroke
				(width 0.1)
				(type default)
			)
			(layer "F.Fab")
		)
		(fp_line
			(start -0.12065 -0.2794)
			(end 0.12065 -0.2794)
			(stroke
				(width 0.1)
				(type default)
			)
			(layer "F.Fab")
		)
		(fp_line
			(start -0.12065 -0.305054)
			(end -0.12065 -0.2794)
			(stroke
				(width 0.1)
				(type default)
			)
			(layer "F.Fab")
		)
		(fp_line
			(start -0.67945 0.3048)
			(end -0.67945 -0.305054)
			(stroke
				(width 0.1)
				(type default)
			)
			(layer "F.Fab")
		)
		(fp_line
			(start -0.67945 -0.305054)
			(end -0.12065 -0.305054)
			(stroke
				(width 0.1)
				(type default)
			)
			(layer "F.Fab")
		)
		(pad "1" smd circle
			(at -0.40005 0 180)
			(size 0 0)
			(layers "F.Cu" "F.Mask" "F.Paste")
			(net "P1V8_RETIMER_CPU0_CS")
		)
		(pad "2" smd circle
			(at 0.40005 0 180)
			(size 0 0)
			(layers "F.Cu" "F.Mask" "F.Paste")
			(net "GND")
		)
	)
	(footprint ""
		(layer "F.Cu")
		(at 339.663278 -172.40631)
		(property "Reference" "TP7"
			(at -3.053842 0 0)
			(unlocked yes)
			(layer "F.SilkS")
			(effects
				(font
					(size 0.7874 0.5842)
					(thickness 0.1524)
				)
				(justify left)
			)
		)
		(property "Value" ""
			(at 0 0 0)
			(layer "F.Fab")
			(effects
				(font
					(size 1.27 1.27)
				)
			)
		)
		(duplicate_pad_numbers_are_jumpers no)
		(pad "1" smd circle
			(at 0 0)
			(size 0.762 0.762)
			(layers "F.Cu" "F.Mask" "F.Paste")
			(net "VSENSE_PVDDCR_CPU0_P0_DP")
		)
	)
)
